(kicad_pcb
	(version 20260206)
	(generator "pcbnew")
	(generator_version "10.0")
	(general
		(thickness 1.6)
		(legacy_teardrops no)
	)
	(paper "A4")
	(title_block
		(title "12092022_DA0F0TMDCD0_F0T_Management_Board_D_brd_V3_OCP.brd")
		(comment 1 "Grand Teton / footprints 962-967 of 1440")
	)
	(layers
		(0 "F.Cu" signal "TOP")
		(4 "In1.Cu" signal "GND")
		(6 "In2.Cu" signal "IN1")
		(8 "In3.Cu" signal "GND1")
		(10 "In4.Cu" signal "IN2")
		(12 "In5.Cu" signal "VCC")
		(14 "In6.Cu" signal "VCC1")
		(16 "In7.Cu" signal "IN3")
		(18 "In8.Cu" signal "GND2")
		(20 "In9.Cu" signal "IN4")
		(22 "In10.Cu" signal "GND3")
		(2 "B.Cu" signal "BOTTOM")
		(9 "F.Adhes" user "F.Adhesive")
		(11 "B.Adhes" user "B.Adhesive")
		(13 "F.Paste" user "Package Geometry/Pastemask Top")
		(15 "B.Paste" user "Package Geometry/Pastemask Bottom")
		(5 "F.SilkS" user "Ref Des/Silkscreen Top")
		(7 "B.SilkS" user "Ref Des/Silkscreen Bottom")
		(1 "F.Mask" user "Board Geometry/Soldermask Top")
		(3 "B.Mask" user "Board Geometry/Soldermask Bottom")
		(17 "Dwgs.User" user "User.Drawings")
		(19 "Cmts.User" user "User.Comments")
		(21 "Eco1.User" user "User.Eco1")
		(23 "Eco2.User" user "User.Eco2")
		(25 "Edge.Cuts" user "Board Geometry/Outline")
		(27 "Margin" user)
		(31 "F.CrtYd" user "Package Geometry/Place Bound Top")
		(29 "B.CrtYd" user "Package Geometry/Place Bound Bottom")
		(35 "F.Fab" user "Ref Des/Assembly Top")
		(33 "B.Fab" user "Ref Des/Assembly Bottom")
	)
	(footprint ""
		(layer "B.Cu")
		(at 53.532024 -45.280326)
		(property "Reference" "C60"
			(at 0 0 0)
			(layer "B.SilkS")
			(hide yes)
			(effects
				(font
					(size 1.27 1.27)
				)
				(justify mirror)
			)
		)
		(property "Value" ""
			(at 0 0 0)
			(layer "B.Fab")
			(effects
				(font
					(size 1.27 1.27)
				)
				(justify mirror)
			)
		)
		(duplicate_pad_numbers_are_jumpers no)
		(fp_line
			(start -0.7874 -0.4064)
			(end -0.7874 0.4064)
			(stroke
				(width 0.1524)
				(type default)
			)
			(layer "B.SilkS")
		)
		(fp_line
			(start -0.7874 0.4064)
			(end 0.7874 0.4064)
			(stroke
				(width 0.1524)
				(type default)
			)
			(layer "B.SilkS")
		)
		(fp_line
			(start 0.7874 -0.4064)
			(end -0.7874 -0.4064)
			(stroke
				(width 0.1524)
				(type default)
			)
			(layer "B.SilkS")
		)
		(fp_line
			(start 0.7874 0.4064)
			(end 0.7874 -0.4064)
			(stroke
				(width 0.1524)
				(type default)
			)
			(layer "B.SilkS")
		)
		(fp_line
			(start -0.67945 -0.3048)
			(end -0.67945 0.3048)
			(stroke
				(width 0.1)
				(type default)
			)
			(layer "B.Fab")
		)
		(fp_line
			(start -0.67945 0.3048)
			(end -0.120396 0.3048)
			(stroke
				(width 0.1)
				(type default)
			)
			(layer "B.Fab")
		)
		(fp_line
			(start -0.12065 -0.3048)
			(end -0.67945 -0.3048)
			(stroke
				(width 0.1)
				(type default)
			)
			(layer "B.Fab")
		)
		(fp_line
			(start -0.12065 -0.2794)
			(end -0.12065 -0.3048)
			(stroke
				(width 0.1)
				(type default)
			)
			(layer "B.Fab")
		)
		(fp_line
			(start -0.120396 0.2794)
			(end 0.12065 0.2794)
			(stroke
				(width 0.1)
				(type default)
			)
			(layer "B.Fab")
		)
		(fp_line
			(start -0.120396 0.3048)
			(end -0.120396 0.2794)
			(stroke
				(width 0.1)
				(type default)
			)
			(layer "B.Fab")
		)
		(fp_line
			(start 0.12065 -0.305054)
			(end 0.12065 -0.2794)
			(stroke
				(width 0.1)
				(type default)
			)
			(layer "B.Fab")
		)
		(fp_line
			(start 0.12065 -0.2794)
			(end -0.12065 -0.2794)
			(stroke
				(width 0.1)
				(type default)
			)
			(layer "B.Fab")
		)
		(fp_line
			(start 0.12065 0.2794)
			(end 0.12065 0.3048)
			(stroke
				(width 0.1)
				(type default)
			)
			(layer "B.Fab")
		)
		(fp_line
			(start 0.12065 0.3048)
			(end 0.67945 0.3048)
			(stroke
				(width 0.1)
				(type default)
			)
			(layer "B.Fab")
		)
		(fp_line
			(start 0.67945 -0.305054)
			(end 0.12065 -0.305054)
			(stroke
				(width 0.1)
				(type default)
			)
			(layer "B.Fab")
		)
		(fp_line
			(start 0.67945 0.3048)
			(end 0.67945 -0.305054)
			(stroke
				(width 0.1)
				(type default)
			)
			(layer "B.Fab")
		)
		(pad "1" smd circle
			(at 0.40005 0 180)
			(size 0 0)
			(layers "B.Cu" "B.Mask" "B.Paste")
			(net "P3V3_STBY_PLLAHVDD")
		)
		(pad "2" smd circle
			(at -0.40005 0 180)
			(size 0 0)
			(layers "B.Cu" "B.Mask" "B.Paste")
			(net "GND")
		)
	)
	(footprint ""
		(layer "B.Cu")
		(at 82.804 -32.766 -90)
		(property "Reference" "C120"
			(at 0 0 90)
			(layer "B.SilkS")
			(hide yes)
			(effects
				(font
					(size 1.27 1.27)
				)
				(justify mirror)
			)
		)
		(property "Value" ""
			(at 0 0 90)
			(layer "B.Fab")
			(effects
				(font
					(size 1.27 1.27)
				)
				(justify mirror)
			)
		)
		(duplicate_pad_numbers_are_jumpers no)
		(fp_line
			(start -1.2954 0.5842)
			(end 1.2954 0.5842)
			(stroke
				(width 0.1524)
				(type default)
			)
			(layer "B.SilkS")
		)
		(fp_line
			(start 1.2954 0.5842)
			(end 1.2954 -0.5842)
			(stroke
				(width 0.1524)
				(type default)
			)
			(layer "B.SilkS")
		)
		(fp_line
			(start -1.2954 -0.5842)
			(end -1.2954 0.5842)
			(stroke
				(width 0.1524)
				(type default)
			)
			(layer "B.SilkS")
		)
		(fp_line
			(start 0 -0.5842)
			(end 0 0.5842)
			(stroke
				(width 0.1524)
				(type default)
			)
			(layer "B.SilkS")
		)
		(fp_line
			(start 1.2954 -0.5842)
			(end -1.2954 -0.5842)
			(stroke
				(width 0.1524)
				(type default)
			)
			(layer "B.SilkS")
		)
		(fp_line
			(start -0.8636 0.4572)
			(end 0.8636 0.4572)
			(stroke
				(width 0.1)
				(type default)
			)
			(layer "B.Fab")
		)
		(fp_line
			(start 0.8636 0.4572)
			(end 0.8636 0.4064)
			(stroke
				(width 0.1)
				(type default)
			)
			(layer "B.Fab")
		)
		(fp_line
			(start -1.1938 0.4064)
			(end -0.8636 0.4064)
			(stroke
				(width 0.1)
				(type default)
			)
			(layer "B.Fab")
		)
		(fp_line
			(start -0.8636 0.4064)
			(end -0.8636 0.4572)
			(stroke
				(width 0.1)
				(type default)
			)
			(layer "B.Fab")
		)
		(fp_line
			(start 0.8636 0.4064)
			(end 1.1938 0.4064)
			(stroke
				(width 0.1)
				(type default)
			)
			(layer "B.Fab")
		)
		(fp_line
			(start 1.1938 0.4064)
			(end 1.1938 -0.4064)
			(stroke
				(width 0.1)
				(type default)
			)
			(layer "B.Fab")
		)
		(fp_line
			(start -1.1938 -0.4064)
			(end -1.1938 0.4064)
			(stroke
				(width 0.1)
				(type default)
			)
			(layer "B.Fab")
		)
		(fp_line
			(start -0.8636 -0.4064)
			(end -1.1938 -0.4064)
			(stroke
				(width 0.1)
				(type default)
			)
			(layer "B.Fab")
		)
		(fp_line
			(start 0.8636 -0.4064)
			(end 0.8636 -0.4572)
			(stroke
				(width 0.1)
				(type default)
			)
			(layer "B.Fab")
		)
		(fp_line
			(start 1.1938 -0.4064)
			(end 0.8636 -0.4064)
			(stroke
				(width 0.1)
				(type default)
			)
			(layer "B.Fab")
		)
		(fp_line
			(start -0.8636 -0.4572)
			(end -0.8636 -0.4064)
			(stroke
				(width 0.1)
				(type default)
			)
			(layer "B.Fab")
		)
		(fp_line
			(start 0.8636 -0.4572)
			(end -0.8636 -0.4572)
			(stroke
				(width 0.1)
				(type default)
			)
			(layer "B.Fab")
		)
		(pad "1" smd rect
			(at 0.7366 0 180)
			(size 0.7112 0.8128)
			(layers "B.Cu" "B.Mask" "B.Paste")
			(net "P3V3_AUX")
		)
		(pad "2" smd rect
			(at -0.7366 0 180)
			(size 0.7112 0.8128)
			(layers "B.Cu" "B.Mask" "B.Paste")
			(net "GND")
		)
	)
	(footprint ""
		(layer "B.Cu")
		(at 49.2252 -88.1126 -90)
		(property "Reference" "R34"
			(at 0 0 90)
			(layer "B.SilkS")
			(hide yes)
			(effects
				(font
					(size 1.27 1.27)
				)
				(justify mirror)
			)
		)
		(property "Value" ""
			(at 0 0 90)
			(layer "B.Fab")
			(effects
				(font
					(size 1.27 1.27)
				)
				(justify mirror)
			)
		)
		(duplicate_pad_numbers_are_jumpers no)
		(fp_line
			(start -0.7874 0.4064)
			(end 0.7874 0.4064)
			(stroke
				(width 0.1524)
				(type default)
			)
			(layer "B.SilkS")
		)
		(fp_line
			(start 0.7874 0.4064)
			(end 0.7874 -0.4064)
			(stroke
				(width 0.1524)
				(type default)
			)
			(layer "B.SilkS")
		)
		(fp_line
			(start -0.7874 -0.4064)
			(end -0.7874 0.4064)
			(stroke
				(width 0.1524)
				(type default)
			)
			(layer "B.SilkS")
		)
		(fp_line
			(start 0.7874 -0.4064)
			(end -0.7874 -0.4064)
			(stroke
				(width 0.1524)
				(type default)
			)
			(layer "B.SilkS")
		)
		(fp_line
			(start -0.67945 0.3048)
			(end -0.120396 0.3048)
			(stroke
				(width 0.1)
				(type default)
			)
			(layer "B.Fab")
		)
		(fp_line
			(start -0.120396 0.3048)
			(end -0.120396 0.2794)
			(stroke
				(width 0.1)
				(type default)
			)
			(layer "B.Fab")
		)
		(fp_line
			(start 0.12065 0.3048)
			(end 0.67945 0.3048)
			(stroke
				(width 0.1)
				(type default)
			)
			(layer "B.Fab")
		)
		(fp_line
			(start 0.67945 0.3048)
			(end 0.67945 -0.305054)
			(stroke
				(width 0.1)
				(type default)
			)
			(layer "B.Fab")
		)
		(fp_line
			(start -0.120396 0.2794)
			(end 0.12065 0.2794)
			(stroke
				(width 0.1)
				(type default)
			)
			(layer "B.Fab")
		)
		(fp_line
			(start 0.12065 0.2794)
			(end 0.12065 0.3048)
			(stroke
				(width 0.1)
				(type default)
			)
			(layer "B.Fab")
		)
		(fp_line
			(start -0.12065 -0.2794)
			(end -0.12065 -0.3048)
			(stroke
				(width 0.1)
				(type default)
			)
			(layer "B.Fab")
		)
		(fp_line
			(start 0.12065 -0.2794)
			(end -0.12065 -0.2794)
			(stroke
				(width 0.1)
				(type default)
			)
			(layer "B.Fab")
		)
		(fp_line
			(start -0.67945 -0.3048)
			(end -0.67945 0.3048)
			(stroke
				(width 0.1)
				(type default)
			)
			(layer "B.Fab")
		)
		(fp_line
			(start -0.12065 -0.3048)
			(end -0.67945 -0.3048)
			(stroke
				(width 0.1)
				(type default)
			)
			(layer "B.Fab")
		)
		(fp_line
			(start 0.12065 -0.305054)
			(end 0.12065 -0.2794)
			(stroke
				(width 0.1)
				(type default)
			)
			(layer "B.Fab")
		)
		(fp_line
			(start 0.67945 -0.305054)
			(end 0.12065 -0.305054)
			(stroke
				(width 0.1)
				(type default)
			)
			(layer "B.Fab")
		)
		(pad "1" smd circle
			(at 0.40005 0 90)
			(size 0 0)
			(layers "B.Cu" "B.Mask" "B.Paste")
			(net "P3V3_RGM")
		)
		(pad "2" smd circle
			(at -0.40005 0 90)
			(size 0 0)
			(layers "B.Cu" "B.Mask" "B.Paste")
			(net "RST_PLTRST_N")
		)
	)
	(footprint ""
		(layer "B.Cu")
		(at 39.80815 -59.0042)
		(property "Reference" "R717"
			(at 0 0 0)
			(layer "B.SilkS")
			(hide yes)
			(effects
				(font
					(size 1.27 1.27)
				)
				(justify mirror)
			)
		)
		(property "Value" ""
			(at 0 0 0)
			(layer "B.Fab")
			(effects
				(font
					(size 1.27 1.27)
				)
				(justify mirror)
			)
		)
		(duplicate_pad_numbers_are_jumpers no)
		(fp_line
			(start -0.7874 -0.4064)
			(end -0.7874 0.4064)
			(stroke
				(width 0.1524)
				(type default)
			)
			(layer "B.SilkS")
		)
		(fp_line
			(start -0.7874 0.4064)
			(end 0.7874 0.4064)
			(stroke
				(width 0.1524)
				(type default)
			)
			(layer "B.SilkS")
		)
		(fp_line
			(start 0.7874 -0.4064)
			(end -0.7874 -0.4064)
			(stroke
				(width 0.1524)
				(type default)
			)
			(layer "B.SilkS")
		)
		(fp_line
			(start 0.7874 0.4064)
			(end 0.7874 -0.4064)
			(stroke
				(width 0.1524)
				(type default)
			)
			(layer "B.SilkS")
		)
		(fp_line
			(start -0.67945 -0.3048)
			(end -0.67945 0.3048)
			(stroke
				(width 0.1)
				(type default)
			)
			(layer "B.Fab")
		)
		(fp_line
			(start -0.67945 0.3048)
			(end -0.120396 0.3048)
			(stroke
				(width 0.1)
				(type default)
			)
			(layer "B.Fab")
		)
		(fp_line
			(start -0.12065 -0.3048)
			(end -0.67945 -0.3048)
			(stroke
				(width 0.1)
				(type default)
			)
			(layer "B.Fab")
		)
		(fp_line
			(start -0.12065 -0.2794)
			(end -0.12065 -0.3048)
			(stroke
				(width 0.1)
				(type default)
			)
			(layer "B.Fab")
		)
		(fp_line
			(start -0.120396 0.2794)
			(end 0.12065 0.2794)
			(stroke
				(width 0.1)
				(type default)
			)
			(layer "B.Fab")
		)
		(fp_line
			(start -0.120396 0.3048)
			(end -0.120396 0.2794)
			(stroke
				(width 0.1)
				(type default)
			)
			(layer "B.Fab")
		)
		(fp_line
			(start 0.12065 -0.305054)
			(end 0.12065 -0.2794)
			(stroke
				(width 0.1)
				(type default)
			)
			(layer "B.Fab")
		)
		(fp_line
			(start 0.12065 -0.2794)
			(end -0.12065 -0.2794)
			(stroke
				(width 0.1)
				(type default)
			)
			(layer "B.Fab")
		)
		(fp_line
			(start 0.12065 0.2794)
			(end 0.12065 0.3048)
			(stroke
				(width 0.1)
				(type default)
			)
			(layer "B.Fab")
		)
		(fp_line
			(start 0.12065 0.3048)
			(end 0.67945 0.3048)
			(stroke
				(width 0.1)
				(type default)
			)
			(layer "B.Fab")
		)
		(fp_line
			(start 0.67945 -0.305054)
			(end 0.12065 -0.305054)
			(stroke
				(width 0.1)
				(type default)
			)
			(layer "B.Fab")
		)
		(fp_line
			(start 0.67945 0.3048)
			(end 0.67945 -0.305054)
			(stroke
				(width 0.1)
				(type default)
			)
			(layer "B.Fab")
		)
		(pad "1" smd circle
			(at 0.40005 0 180)
			(size 0 0)
			(layers "B.Cu" "B.Mask" "B.Paste")
			(net "P3V3_AUX")
		)
		(pad "2" smd circle
			(at -0.40005 0 180)
			(size 0 0)
			(layers "B.Cu" "B.Mask" "B.Paste")
			(net "RST_BMC_RSTBTN_OUT_N")
		)
	)
	(footprint ""
		(layer "B.Cu")
		(at 18.259552 -90.786966 180)
		(property "Reference" "C167"
			(at 0 0 0)
			(layer "B.SilkS")
			(hide yes)
			(effects
				(font
					(size 1.27 1.27)
				)
				(justify mirror)
			)
		)
		(property "Value" ""
			(at 0 0 0)
			(layer "B.Fab")
			(effects
				(font
					(size 1.27 1.27)
				)
				(justify mirror)
			)
		)
		(duplicate_pad_numbers_are_jumpers no)
		(fp_line
			(start 0.69215 0.2921)
			(end 0.69215 -0.2921)
			(stroke
				(width 0.1524)
				(type default)
			)
			(layer "B.SilkS")
		)
		(fp_line
			(start 0.69215 -0.2921)
			(end -0.69215 -0.2921)
			(stroke
				(width 0.1524)
				(type default)
			)
			(layer "B.SilkS")
		)
		(fp_line
			(start -0.69215 0.2921)
			(end 0.69215 0.2921)
			(stroke
				(width 0.1524)
				(type default)
			)
			(layer "B.SilkS")
		)
		(fp_line
			(start -0.69215 -0.2921)
			(end -0.69215 0.2921)
			(stroke
				(width 0.1524)
				(type default)
			)
			(layer "B.SilkS")
		)
		(fp_line
			(start 0.51435 0.2794)
			(end 0.51435 -0.2794)
			(stroke
				(width 0.1)
				(type default)
			)
			(layer "B.Fab")
		)
		(fp_line
			(start 0.51435 -0.2794)
			(end -0.51435 -0.2794)
			(stroke
				(width 0.1)
				(type default)
			)
			(layer "B.Fab")
		)
		(fp_line
			(start -0.51435 0.2794)
			(end 0.51435 0.2794)
			(stroke
				(width 0.1)
				(type default)
			)
			(layer "B.Fab")
		)
		(fp_line
			(start -0.51435 -0.2794)
			(end -0.51435 0.2794)
			(stroke
				(width 0.1)
				(type default)
			)
			(layer "B.Fab")
		)
		(pad "1" smd circle
			(at 0.40005 0)
			(size 0 0)
			(layers "B.Cu" "B.Mask" "B.Paste")
			(net "VCCIO1")
		)
		(pad "2" smd circle
			(at -0.40005 0)
			(size 0 0)
			(layers "B.Cu" "B.Mask" "B.Paste")
			(net "GND")
		)
		(zone
			(layer "B.Cu")
			(hatch none 0.5)
			(connect_pads
				(clearance 0)
			)
			(min_thickness 0.25)
			(keepout
				(tracks not_allowed)
				(vias allowed)
				(pads allowed)
				(copperpour not_allowed)
				(footprints allowed)
			)
			(placement
				(enabled no)
				(sheetname "")
			)
			(fill
				(thermal_gap 0.5)
				(thermal_bridge_width 0.5)
				(island_removal_mode 0)
			)
			(polygon
				(pts
					(xy 18.069052 -90.874596) (xy 18.160492 -90.932762) (xy 18.359882 -90.932762) (xy 18.450052 -90.874596)
					(xy 18.450052 -90.699336) (xy 18.359882 -90.640916) (xy 18.160492 -90.640916) (xy 18.069052 -90.699082)
				)
			)
		)
	)
	(footprint ""
		(layer "B.Cu")
		(at 81.129886 -42.006012)
		(property "Reference" "R329"
			(at 0 0 0)
			(layer "B.SilkS")
			(hide yes)
			(effects
				(font
					(size 1.27 1.27)
				)
				(justify mirror)
			)
		)
		(property "Value" ""
			(at 0 0 0)
			(layer "B.Fab")
			(effects
				(font
					(size 1.27 1.27)
				)
				(justify mirror)
			)
		)
		(duplicate_pad_numbers_are_jumpers no)
		(fp_line
			(start -0.7874 -0.4064)
			(end -0.7874 0.4064)
			(stroke
				(width 0.1524)
				(type default)
			)
			(layer "B.SilkS")
		)
		(fp_line
			(start -0.7874 0.4064)
			(end 0.7874 0.4064)
			(stroke
				(width 0.1524)
				(type default)
			)
			(layer "B.SilkS")
		)
		(fp_line
			(start 0.7874 -0.4064)
			(end -0.7874 -0.4064)
			(stroke
				(width 0.1524)
				(type default)
			)
			(layer "B.SilkS")
		)
		(fp_line
			(start 0.7874 0.4064)
			(end 0.7874 -0.4064)
			(stroke
				(width 0.1524)
				(type default)
			)
			(layer "B.SilkS")
		)
		(fp_line
			(start -0.67945 -0.3048)
			(end -0.67945 0.3048)
			(stroke
				(width 0.1)
				(type default)
			)
			(layer "B.Fab")
		)
		(fp_line
			(start -0.67945 0.3048)
			(end -0.120396 0.3048)
			(stroke
				(width 0.1)
				(type default)
			)
			(layer "B.Fab")
		)
		(fp_line
			(start -0.12065 -0.3048)
			(end -0.67945 -0.3048)
			(stroke
				(width 0.1)
				(type default)
			)
			(layer "B.Fab")
		)
		(fp_line
			(start -0.12065 -0.2794)
			(end -0.12065 -0.3048)
			(stroke
				(width 0.1)
				(type default)
			)
			(layer "B.Fab")
		)
		(fp_line
			(start -0.120396 0.2794)
			(end 0.12065 0.2794)
			(stroke
				(width 0.1)
				(type default)
			)
			(layer "B.Fab")
		)
		(fp_line
			(start -0.120396 0.3048)
			(end -0.120396 0.2794)
			(stroke
				(width 0.1)
				(type default)
			)
			(layer "B.Fab")
		)
		(fp_line
			(start 0.12065 -0.305054)
			(end 0.12065 -0.2794)
			(stroke
				(width 0.1)
				(type default)
			)
			(layer "B.Fab")
		)
		(fp_line
			(start 0.12065 -0.2794)
			(end -0.12065 -0.2794)
			(stroke
				(width 0.1)
				(type default)
			)
			(layer "B.Fab")
		)
		(fp_line
			(start 0.12065 0.2794)
			(end 0.12065 0.3048)
			(stroke
				(width 0.1)
				(type default)
			)
			(layer "B.Fab")
		)
		(fp_line
			(start 0.12065 0.3048)
			(end 0.67945 0.3048)
			(stroke
				(width 0.1)
				(type default)
			)
			(layer "B.Fab")
		)
		(fp_line
			(start 0.67945 -0.305054)
			(end 0.12065 -0.305054)
			(stroke
				(width 0.1)
				(type default)
			)
			(layer "B.Fab")
		)
		(fp_line
			(start 0.67945 0.3048)
			(end 0.67945 -0.305054)
			(stroke
				(width 0.1)
				(type default)
			)
			(layer "B.Fab")
		)
		(pad "1" smd circle
			(at 0.40005 0 180)
			(size 0 0)
			(layers "B.Cu" "B.Mask" "B.Paste")
			(net "GND")
		)
		(pad "2" smd circle
			(at -0.40005 0 180)
			(size 0 0)
			(layers "B.Cu" "B.Mask" "B.Paste")
			(net "M_BMC_DDR4_MA<3>")
		)
	)
)
